# S9S_MB_2U (Grand Teton) — schematic netlist excerpt (pin names and nets, part order shuffled) for the footprints in the layout excerpt that follows; sources: Cadence DE-HDL packaged netlist, KiCad conversion of 03242023_DA0F0TMBIJ0_F0T_Motherboard_J_brd_V01_OCP.brd

D44  SCHOTTKY_12  B0530WS7F IC  pkg SOD323XB  page 115 : A = PWRGD_FAIL_CPU0_EF_R1 ; C = P3V3_AUX
PC576_P1_1  Q_CAP  22UF 4V 20% X6S  pkg C0805  page 285 : A = PVCCIN_CPU1 ; B = GND

(kicad_pcb
	(version 20260206)
	(generator "pcbnew")
	(generator_version "10.0")
	(general
		(thickness 1.6)
		(legacy_teardrops no)
	)
	(paper "A4")
	(title_block
		(title "03242023_DA0F0TMBIJ0_F0T_Motherboard_J_brd_V01_OCP.brd")
		(comment 1 "Grand Teton / footprints 5204-5205 of 6105")
	)
	(layers
		(0 "F.Cu" signal "TOP")
		(4 "In1.Cu" signal "GND")
		(6 "In2.Cu" signal "IN1")
		(8 "In3.Cu" signal "GND1")
		(10 "In4.Cu" signal "IN2")
		(12 "In5.Cu" signal "GND2")
		(14 "In6.Cu" signal "IN3")
		(16 "In7.Cu" signal "GND3")
		(18 "In8.Cu" signal "VCC")
		(20 "In9.Cu" signal "VCC1")
		(22 "In10.Cu" signal "GND4")
		(24 "In11.Cu" signal "IN4")
		(26 "In12.Cu" signal "GND5")
		(28 "In13.Cu" signal "IN5")
		(30 "In14.Cu" signal "GND6")
		(32 "In15.Cu" signal "IN6")
		(34 "In16.Cu" signal "GND7")
		(2 "B.Cu" signal "BOTTOM")
		(9 "F.Adhes" user "F.Adhesive")
		(11 "B.Adhes" user "B.Adhesive")
		(13 "F.Paste" user "Package Geometry/Pastemask Top")
		(15 "B.Paste" user "Package Geometry/Pastemask Bottom")
		(5 "F.SilkS" user "Ref Des/Silkscreen Top")
		(7 "B.SilkS" user "Ref Des/Silkscreen Bottom")
		(1 "F.Mask" user "Board Geometry/Soldermask Top")
		(3 "B.Mask" user "Board Geometry/Soldermask Bottom")
		(17 "Dwgs.User" user "User.Drawings")
		(19 "Cmts.User" user "User.Comments")
		(21 "Eco1.User" user "User.Eco1")
		(23 "Eco2.User" user "User.Eco2")
		(25 "Edge.Cuts" user "Board Geometry/Outline")
		(27 "Margin" user)
		(31 "F.CrtYd" user "Package Geometry/Place Bound Top")
		(29 "B.CrtYd" user "Package Geometry/Place Bound Bottom")
		(35 "F.Fab" user "Ref Des/Assembly Top")
		(33 "B.Fab" user "Ref Des/Assembly Bottom")
	)
	(footprint ""
		(layer "B.Cu")
		(at 95.614998 -324.753986 -90)
		(property "Reference" "PC576_P1_1"
			(at 0 0 90)
			(layer "B.SilkS")
			(hide yes)
			(effects
				(font
					(size 1.27 1.27)
				)
				(justify mirror)
			)
		)
		(property "Value" ""
			(at 0 0 90)
			(layer "B.Fab")
			(effects
				(font
					(size 1.27 1.27)
				)
				(justify mirror)
			)
		)
		(duplicate_pad_numbers_are_jumpers no)
		(fp_line
			(start -1.524 0.762)
			(end 1.524 0.762)
			(stroke
				(width 0.1524)
				(type default)
			)
			(layer "B.SilkS")
		)
		(fp_line
			(start 1.524 0.762)
			(end 1.524 -0.762)
			(stroke
				(width 0.1524)
				(type default)
			)
			(layer "B.SilkS")
		)
		(fp_line
			(start -1.524 -0.762)
			(end -1.524 0.762)
			(stroke
				(width 0.1524)
				(type default)
			)
			(layer "B.SilkS")
		)
		(fp_line
			(start 1.524 -0.762)
			(end -1.524 -0.762)
			(stroke
				(width 0.1524)
				(type default)
			)
			(layer "B.SilkS")
		)
		(fp_line
			(start -1.1049 0.724916)
			(end -1.1049 -0.724916)
			(stroke
				(width 0.1)
				(type default)
			)
			(layer "B.Fab")
		)
		(fp_line
			(start 1.1049 0.724916)
			(end -1.1049 0.724916)
			(stroke
				(width 0.1)
				(type default)
			)
			(layer "B.Fab")
		)
		(fp_line
			(start -1.1049 -0.724916)
			(end 1.1049 -0.724916)
			(stroke
				(width 0.1)
				(type default)
			)
			(layer "B.Fab")
		)
		(fp_line
			(start 1.1049 -0.724916)
			(end 1.1049 0.724916)
			(stroke
				(width 0.1)
				(type default)
			)
			(layer "B.Fab")
		)
		(pad "1" smd rect
			(at 0.889 0 270)
			(size 1.016 1.27)
			(layers "B.Cu" "B.Mask" "B.Paste")
			(net "PVCCIN_CPU1")
		)
		(pad "2" smd rect
			(at -0.889 0 270)
			(size 1.016 1.27)
			(layers "B.Cu" "B.Mask" "B.Paste")
			(net "GND")
		)
	)
	(footprint ""
		(layer "B.Cu")
		(at 433.14874 -313.913266 180)
		(property "Reference" "D44"
			(at 2.36474 0.731012 0)
			(unlocked yes)
			(layer "B.SilkS")
			(effects
				(font
					(size 0.7874 0.5842)
					(thickness 0.1524)
				)
				(justify left mirror)
			)
		)
		(property "Value" ""
			(at 0 0 0)
			(layer "B.Fab")
			(effects
				(font
					(size 1.27 1.27)
				)
				(justify mirror)
			)
		)
		(duplicate_pad_numbers_are_jumpers no)
		(fp_line
			(start 2.050796 0.700024)
			(end 2.050796 -0.700024)
			(stroke
				(width 0.1524)
				(type default)
			)
			(layer "B.SilkS")
		)
		(fp_line
			(start 2.050796 -0.700024)
			(end -2.050796 -0.700024)
			(stroke
				(width 0.1524)
				(type default)
			)
			(layer "B.SilkS")
		)
		(fp_line
			(start 0.30607 0.500126)
			(end -0.193802 0)
			(stroke
				(width 0.1524)
				(type default)
			)
			(layer "B.SilkS")
		)
		(fp_line
			(start 0.30607 -0.500126)
			(end 0.30607 0.500126)
			(stroke
				(width 0.1524)
				(type default)
			)
			(layer "B.SilkS")
		)
		(fp_line
			(start -0.193802 0)
			(end 0.30607 -0.500126)
			(stroke
				(width 0.1524)
				(type default)
			)
			(layer "B.SilkS")
		)
		(fp_line
			(start -0.293878 -0.500126)
			(end -0.293878 0.500126)
			(stroke
				(width 0.1524)
				(type default)
			)
			(layer "B.SilkS")
		)
		(fp_line
			(start -2.050796 0.700024)
			(end 2.050796 0.700024)
			(stroke
				(width 0.1524)
				(type default)
			)
			(layer "B.SilkS")
		)
		(fp_line
			(start -2.050796 -0.700024)
			(end -2.050796 0.700024)
			(stroke
				(width 0.1524)
				(type default)
			)
			(layer "B.SilkS")
		)
		(fp_line
			(start -2.051304 0.6985)
			(end -2.051304 0.635)
			(stroke
				(width 0.1524)
				(type default)
			)
			(layer "B.SilkS")
		)
		(fp_line
			(start -2.051304 0.635)
			(end -2.152904 0.635)
			(stroke
				(width 0.1524)
				(type default)
			)
			(layer "B.SilkS")
		)
		(fp_line
			(start -2.064004 -0.6731)
			(end -2.064004 -0.6985)
			(stroke
				(width 0.1524)
				(type default)
			)
			(layer "B.SilkS")
		)
		(fp_line
			(start -2.064004 -0.6985)
			(end -2.229104 -0.6985)
			(stroke
				(width 0.1524)
				(type default)
			)
			(layer "B.SilkS")
		)
		(fp_line
			(start -2.152904 0.635)
			(end -2.152904 -0.6985)
			(stroke
				(width 0.1524)
				(type default)
			)
			(layer "B.SilkS")
		)
		(fp_line
			(start -2.152904 -0.6985)
			(end -2.343404 -0.6985)
			(stroke
				(width 0.1524)
				(type default)
			)
			(layer "B.SilkS")
		)
		(fp_line
			(start -2.229104 0.6985)
			(end -2.051304 0.6985)
			(stroke
				(width 0.1524)
				(type default)
			)
			(layer "B.SilkS")
		)
		(fp_line
			(start -2.229104 -0.6985)
			(end -2.229104 0.6985)
			(stroke
				(width 0.1524)
				(type default)
			)
			(layer "B.SilkS")
		)
		(fp_line
			(start -2.343404 0.6985)
			(end -2.216404 0.6985)
			(stroke
				(width 0.1524)
				(type default)
			)
			(layer "B.SilkS")
		)
		(fp_line
			(start -2.343404 -0.6985)
			(end -2.343404 0.6985)
			(stroke
				(width 0.1524)
				(type default)
			)
			(layer "B.SilkS")
		)
		(fp_line
			(start 0.899922 0.700024)
			(end 0.899922 -0.700024)
			(stroke
				(width 0.1)
				(type default)
			)
			(layer "B.Fab")
		)
		(fp_line
			(start 0.899922 -0.700024)
			(end -0.899922 -0.700024)
			(stroke
				(width 0.1)
				(type default)
			)
			(layer "B.Fab")
		)
		(fp_line
			(start -0.899922 0.700024)
			(end 0.899922 0.700024)
			(stroke
				(width 0.1)
				(type default)
			)
			(layer "B.Fab")
		)
		(fp_line
			(start -0.899922 -0.700024)
			(end -0.899922 0.700024)
			(stroke
				(width 0.1)
				(type default)
			)
			(layer "B.Fab")
		)
		(fp_text user "+"
			(at 3.72999 0.503682 90)
			(unlocked yes)
			(layer "B.SilkS")
			(effects
				(font
					(size 1.905 1.4224)
					(thickness 0.1524)
				)
				(justify left mirror)
			)
		)
		(fp_text user "-"
			(at -4.261104 0.10795 0)
			(unlocked yes)
			(layer "B.SilkS")
			(effects
				(font
					(size 1.905 1.4224)
					(thickness 0.1524)
				)
				(justify left mirror)
			)
		)
		(fp_text user "+"
			(at 3.123946 0.762 90)
			(unlocked yes)
			(layer "B.Fab")
			(effects
				(font
					(size 1.905 1.4224)
					(thickness 0.1524)
				)
				(justify left mirror)
			)
		)
		(fp_text user "-"
			(at -3.880104 0.23495 0)
			(unlocked yes)
			(layer "B.Fab")
			(effects
				(font
					(size 1.905 1.4224)
					(thickness 0.1524)
				)
				(justify left mirror)
			)
		)
		(pad "1" smd rect
			(at 1.199896 0 90)
			(size 0.6604 1.3716)
			(layers "B.Cu" "B.Mask" "B.Paste")
			(net "PWRGD_FAIL_CPU0_EF_R1")
		)
		(pad "2" smd rect
			(at -1.199896 0 270)
			(size 0.6604 1.3716)
			(layers "B.Cu" "B.Mask" "B.Paste")
			(net "P3V3_AUX")
		)
	)
)
